#ISCELL
  logical_power design_note *
  *
#ISCELL
  mstr_misc dns *
  *
#ISCELL
  pure_quanta quanta_title_block_c *
  *
#CELL
  pure_quanta q_res *
  page119_i100
#CELL
  pure_quanta q_res *
  page119_i101
#ISCELL
  logical_power universal_power *
  page119_i102
#ISCELL
  standard offpage *
  page119_i103
#ISCELL
  standard offpage *
  page119_i104
#ISCELL
  standard offpage *
  page119_i105
#ISCELL
  standard offpage *
  page119_i106
#ISCELL
  standard offpage *
  page119_i107
#ISCELL
  standard offpage *
  page119_i108
#ISCELL
  standard offpage *
  page119_i109
#ISCELL
  standard offpage *
  page119_i110
#ISCELL
  standard offpage *
  page119_i111
#ISCELL
  standard offpage *
  page119_i112
#ISCELL
  standard offpage *
  page119_i113
#ISCELL
  standard offpage *
  page119_i114
#CELL
  pure_quanta q_res *
  page119_i116
#ISCELL
  standard offpage *
  page119_i120
#ISCELL
  standard offpage *
  page119_i121
#ISCELL
  standard offpage *
  page119_i124
#CELL
  pure_quanta q_res *
  page119_i125
#CELL
  pure_quanta q_res *
  page119_i135
#CELL
  pure_quanta q_res *
  page119_i136
#ISCELL
  standard offpage *
  page119_i137
#ISCELL
  logical_power universal_power *
  page119_i138
#CELL
  pure_quanta q_res *
  page119_i139
#ISCELL
  logical_power universal_power *
  page119_i141
#ISCELL
  standard offpage *
  page119_i142
#ISCELL
  standard offpage *
  page119_i143
#ISCELL
  standard offpage *
  page119_i144
#ISCELL
  standard offpage *
  page119_i145
#ISCELL
  standard offpage *
  page119_i146
#CELL
  pure_quanta q_res *
  page119_i147
#CELL
  pure_quanta q_res *
  page119_i148
#ISCELL
  logical_power universal_power *
  page119_i149
#CELL
  pure_quanta q_res *
  page119_i150
#CELL
  pure_quanta q_res *
  page119_i151
#CELL
  pure_quanta q_res *
  page119_i152
#ISCELL
  standard offpage *
  page119_i155
#CELL
  pure_quanta q_res *
  page119_i156
#ISCELL
  standard offpage *
  page119_i157
#CELL
  pure_quanta q_res *
  page119_i158
#ISCELL
  standard offpage *
  page119_i159
#CELL
  pure_quanta q_res *
  page119_i160
#CELL
  pure_quanta q_res *
  page119_i161
#ISCELL
  standard offpage *
  page119_i162
#CELL
  pure_quanta q_res *
  page119_i163
#ISCELL
  standard offpage *
  page119_i164
#ISCELL
  standard offpage *
  page119_i167
#ISCELL
  standard offpage *
  page119_i168
#CELL
  pure_quanta q_res *
  page119_i169
#CELL
  pure_quanta q_res *
  page119_i170
#ISCELL
  logical_power universal_gnd *
  page119_i171
#CELL
  pure_quanta q_res *
  page119_i172
#ISCELL
  standard offpage *
  page119_i173
#ISCELL
  standard offpage *
  page119_i174
#ISCELL
  standard offpage *
  page119_i175
#CELL
  pure_quanta q_res *
  page119_i176
#CELL
  pure_quanta q_res *
  page119_i177
#ISCELL
  standard offpage *
  page119_i178
#ISCELL
  logical_power universal_power *
  page119_i18
#CELL
  pure_quanta q_res *
  page119_i196
#ISCELL
  logical_power universal_gnd *
  page119_i197
#ISCELL
  standard offpage *
  page119_i199
#ISCELL
  logical_power universal_power *
  page119_i210
#CELL
  pure_quanta q_res *
  page119_i211
#ISCELL
  standard offpage *
  page119_i212
#ISCELL
  logical_power universal_gnd *
  page119_i213
#ISCELL
  logical_power universal_power *
  page119_i214
#CELL
  pure_quanta q_res *
  page119_i215
#CELL
  pure_quanta q_res *
  page119_i216
#ISCELL
  standard offpage *
  page119_i217
#ISCELL
  logical_power universal_power *
  page119_i218
#CELL
  pure_quanta q_res *
  page119_i219
#CELL
  pure_quanta q_res *
  page119_i220
#ISCELL
  logical_power universal_gnd *
  page119_i221
#ISCELL
  standard offpage *
  page119_i222
#ISCELL
  logical_power universal_power *
  page119_i223
#CELL
  pure_quanta q_res *
  page119_i224
#CELL
  pure_quanta q_res *
  page119_i225
#ISCELL
  logical_power universal_gnd *
  page119_i226
#ISCELL
  standard offpage *
  page119_i29
#ISCELL
  standard offpage *
  page119_i40
#ISCELL
  logical_power universal_gnd *
  page119_i44
#ISCELL
  standard offpage *
  page119_i49
#ISCELL
  standard offpage *
  page119_i50
#CELL
  pure_quanta q_res *
  page119_i53
#CELL
  pure_quanta q_res *
  page119_i54
#ISCELL
  standard offpage *
  page119_i56
#CELL
  pure_quanta q_res *
  page119_i57
#CELL
  pure_quanta q_res *
  page119_i58
#ISCELL
  standard offpage *
  page119_i59
#ISCELL
  standard offpage *
  page119_i60
#CELL
  pure_quanta q_res *
  page119_i61
#CELL
  pure_quanta q_res *
  page119_i62
#ISCELL
  standard offpage *
  page119_i63
#ISCELL
  standard offpage *
  page119_i65
#CELL
  pure_quanta q_res *
  page119_i66
#ISCELL
  standard offpage *
  page119_i67
#CELL
  pure_quanta q_res *
  page119_i68
#CELL
  pure_quanta q_res *
  page119_i71
#CELL
  pure_quanta q_res *
  page119_i72
#CELL
  pure_quanta q_res *
  page119_i88
#CELL
  pure_quanta q_res *
  page119_i89
#CELL
  pure_quanta q_res *
  page119_i90
#ISCELL
  logical_power universal_power *
  page119_i91
#CELL
  pure_quanta q_res *
  page119_i92
#CELL
  pure_quanta q_res *
  page119_i93
#CELL
  pure_quanta q_res *
  page119_i94
#CELL
  pure_quanta q_res *
  page119_i95
#CELL
  pure_quanta q_res *
  page119_i96
#CELL
  pure_quanta q_res *
  page119_i97
#CELL
  pure_quanta q_res *
  page119_i98
